# BARRELEYE_G2-FPDB_POST-EVT-HW-EBOM-X00_20161123-add_2nd_source_X08-20161215-Final-b.xls — FPDB (bom)
| FOXCONN TECHNOLOGY GROUP |  |  |  |  |  |  |  |  |  |  |  |  |  |  |  |  |  |  |
| BILL OF MATERIAL |  |  |  |  |  |  |  |  |  |  |  |  |  |  |  |  |  |  |
| REV OF  BOM | X07 | CUSTOMER |  | <name> |  | CUSTOMER P/N |  | PWA P/N： | PWA DESCRIPTION |  |  |  | PRODUCT CODE |  |  | PWA  REV |  | DATE |
| Sourcing (Single/Sole/Multi) | Critical Commodity (Y or N) | Component Class (1, 2, other) | Customer PSL (Y or N) | Line Item | Item Number | Foxconn P/N | Customer P/N | Part Description | Manufacturer  Full Name | Manufacturer  Part Number | Qty | RoHS Status | Location | CC Qual Build: | Qual by (Customer / ODM ?) | The Date of Change Part or Add 2nd Source | Configuration Identifier | Customer Comments |
|  |  |  |  | 1 | 1 | 0101E1E00-000-G |  | PCB,Zaius-Fan Board EVT-X00,OSP,Red,6L,1.300*2.362,G | GCE | 0101E1E00-000-G | 1 |  | PCB |  |  |  |  |  |
|  |  |  |  |  | 1 | 0101E1E00-000-G |  | PCB,Zaius-Fan Board EVT-X00,OSP,Red,6L,1.300*2.362,G | FOUNDER | 0101E1E00-000-G |  |  |  |  |  |  |  |  |
|  |  |  |  | 2 | 2 | 620103700-015-G | - | CAP,100nF,+/-10%,X7R,10V,G,SMD0402 | MURATA | GRM155R71A104K | 20 |  | C1,C2,C3,PHAC5,C18,C19,C22,C24,C26,C28,C30,C32,C34,C35,C2111,C2112,C2113,C2114,C2115,C2116 |  |  |  |  |  |
|  |  |  |  |  | 2 | 620103700-012-G |  | CAP,0.1uF,+/-10%,X7R,10V,G,SMD0402 | WALSIN | 0402B104K100CT |  |  |  |  |  |  |  |  |
|  |  |  |  |  | 2 | 620103700-023-G |  | CAP,100nF,+/-10%,X7R,10V,G,SMD0402 | TAIYO | LMK105B7104KV-F |  |  |  |  |  |  |  |  |
|  |  |  |  |  | 2 | 620103700-026-G |  | CAP,100nF,+/-10%,X7R,10V,G,SMD0402 | SAMSUNG | CL05B104KP5NNNC |  |  |  |  |  |  |  |  |
|  |  |  |  | 3 | 3 | 62010BN00-015-G | - | CAP,1uF,+/-10%,X5R,6.3V,G,SMD0402 | MURATA | GRM155R60J105K | 2 |  | C4,C11 |  |  |  |  |  |
|  |  |  |  |  | 3 | 62010BN01-023-G |  | CAP,1uF,+/-10%,X5R,6.3V,G,SMD0402 | TAIYO | JMK105BJ105KV-F |  |  |  |  |  |  |  |  |
|  |  |  |  |  | 3 | 62010BN00-026-G |  | CAP,1uF,+/-10%,X5R,6.3V,G,SMD0402 | SAMSUNG | CL05A105KQ5NNNC |  |  |  |  |  |  |  |  |
|  |  |  |  | 4 | 4 | 620106200-015-G | - | CAP,10nF,+/-10%,X7R,16V,G,SMD0402 | MURATA | GRM155R71C103K | 2 |  | C5,C12 |  |  |  |  |  |
|  |  |  |  |  | 4 | 620106200-012-G |  | CAP,10nF,+/-10%,X7R,16V,G,SMD0402 | WALSIN | 0402B103K160CT |  |  |  |  |  |  |  |  |
|  |  |  |  |  | 4 | 620106200-026-G |  | CAP,10nF,+/-10%,X7R,16V,G,SMD0402 | SAMSUNG | CL05B103KO5NNNC |  |  |  |  |  |  |  |  |
|  |  |  |  |  | 4 | 620106200-023-G |  | CAP,10nF,+/-10%,X7R,16V,G,SMD0402 | TAIYO | EMK105B7103KV-F |  |  |  |  |  |  |  |  |
|  |  |  |  | 5 | 5 | 620101T02-015-G | - | CAP,100nF,+/-10%,X7R,16V,G,SMD0402 | MURATA | GRM155R71C104K | 14 |  | C6,C7,C9,PSRC10,C13,C14,C16,C20,C21,C38,C39,C46,C362,C394 |  |  |  |  |  |
|  |  |  |  |  | 5 | 620101T00-012-G |  | CAP,100nF,+/-10%,X7R,16V,G,SMD0402 | WALSIN | 0402B104K160CT |  |  |  |  |  |  |  |  |
|  |  |  |  |  | 5 | 620101T00-026-G |  | CAP,100nF,+/-10%,X7R,16V,G,SMD0402 | SAMSUNG | CL05B104KO5NNNC |  |  |  |  |  |  |  |  |
|  |  |  |  |  | 5 | 620101T00-015-G |  | CAP,100nF,+/-10%,X7R,16V,G,SMD0402 | MURATA | GRM155R71C104KA88D |  |  |  |  |  |  |  |  |
|  |  |  |  | 6 | 6 | 620130V00-015-G |  | CAP,10uF,+/-20%,X6S,16V,G,SMD0603 | MURATA | GRM188C81C106MA73D | 16 |  | C8,C10,C15,C17,C23,C25,C27,C29,C31,C33,C40,C43,C47,C50,C53,C56 |  |  |  |  |  |
|  |  |  |  |  | 6 | 620130V00-023-G |  | CAP,10uF,+/-20%,X6S,16V,G,SMD0603 | TAIYO | EMK107BC6106MA-T |  |  |  |  |  |  |  |  |
|  |  |  |  | 7 | 7 | 620103K00-015-G | - | CAP,1nF,+/-10%,X7R,50V,G,SMD0402 | MURATA | GRM155R71H102K | 3 |  | PHAC2,C36,C37 |  |  |  |  |  |
|  |  |  |  |  | 7 | 620103K00-012-G |  | CAP,1nF,+/-10%,X7R,50V,G,SMD0402 | WALSIN | 0402B102K500CT |  |  |  |  |  |  |  |  |
|  |  |  |  |  | 7 | 620103K00-026-G |  | CAP,1nF,+/-10%,X7R,50V,G,SMD0402 | SAMSUNG | CL05B102KB5NNNC |  |  |  |  |  |  |  |  |
|  |  |  |  |  | 7 | 620103K00-023-G |  | CAP,1nF,+/-10%,X7R,50V,G,SMD0402 | TAIYO | UMK105B7102KV-F |  |  |  |  |  |  |  |  |
|  |  |  |  | 8 | 8 | 620100L00-015-G | - | CAP,22pF,+/-5%,NPO(C0G),50V,G,SMD0402 | MURATA | GRM1555C1H220J | 12 |  | C41,C42,C44,C45,C48,C49,C51,C52,C54,C55,C57,C58 |  |  |  |  |  |
|  |  |  |  |  | 8 | 620100L08-012-G |  | CAP,22pF,+/-5%,NPO(C0G),50V,G,SMD0402 | WALSIN | 0402N220J500CT |  |  |  |  |  |  |  |  |
|  |  |  |  |  | 8 | 620100L00-026-G |  | CAP,22pF,+/-5%,NPO(C0G),50V,G,SMD0402 | SAMSUNG | CL05C220JB5NNNC |  |  |  |  |  |  |  |  |
|  |  |  |  |  | 8 | 620100L00-023-G |  | CAP,22pF,+/-5%,NPO(C0G),50V,G,SMD0402 | TAIYO | UMK105CG220JV-F |  |  |  |  |  |  |  |  |
|  |  |  |  | 9 | 9 | 62012FR00-015-G |  | CAP,10uF,+/-20%,X5R,25V,G,SMD0603 | MURATA | GRM188R61E106M | 2 |  | C398,C399 |  |  |  |  |  |
|  |  |  |  |  | 9 | 62012FR00-023-G |  | CAP,10uF,+/-20%,X5R,25V,G,SMD0603 | TAIYO | TMK107BBJ106MA-T |  |  |  |  |  |  |  |  |
|  |  |  |  |  | 9 | 62012FR00-026-G |  | CAP,10uF,+/-20%,X5R,25V,G,SMD0603 | SAMSUNG | CL10A106MA8NRNC |  |  |  |  |  |  |  |  |
|  |  |  |  | 10 | 10 | 620100D00-015-G |  | CAP,100nF,+/-10%,X7R,16V,G,SMD0603 | MURATA | GRM188R71C104K | 1 |  | C400 |  |  |  |  |  |
|  |  |  |  |  | 10 | 620100D00-012-G |  | CAP,100nF,+/-10%,X7R,16V,G,SMD0603 | WALSIN | 0603B104K160CT |  |  |  |  |  |  |  |  |
|  |  |  |  |  | 10 | 620100D00-026-G |  | CAP,100nF,+/-10%,X7R,16V,G,SMD0603 | SAMSUNG | CL10B104KO8NNNC |  |  |  |  |  |  |  |  |
|  |  |  |  | 11 | 11 | 62012A400-015-G | - | CAP,100nF,+/-10%,X7R,25V,G,SMD0402 | MURATA | GRM155R71E104KE14D | 7 |  | PSRC1,PSUC3,PEUC3,PSRC6,PHAC19,PHAC20,C2117 |  |  |  |  |  |
|  |  |  |  |  | 11 | 62012A400-023-G |  | CAP,100nF,+/-10%,X7R,25V,G,SMD0402 | TAIYO | TMK105B7104KV-FR |  |  |  |  |  |  |  |  |
|  |  |  |  |  | 11 | 62012A400-026-G |  | CAP,100nF,+/-10%,X7R,25V,G,SMD0402 | SAMSUNG | CL05B104KA5NNNC |  |  |  |  |  |  |  |  |
|  |  |  |  |  | 11 | 62012A400-012-G |  | CAP,100nF,+/-10%,X7R,25V,G,SMD0402 | WALSIN | 0402B104K250CT |  |  |  |  |  |  |  |  |
|  |  |  |  | 12 | 12 | 62010VD00-015-G |  | CAP,100nF,+/-10%,X7R,100V,G,SMD0603 | MURATA | GRM188R72A104K | 2 |  | PHAC14,C2118 |  |  |  |  |  |
|  |  |  |  |  |  | 62010VD00-026-G |  | CAP,100nF,+/-10%,X7R,100V,G,SMD0603 | SAMSUNG | CL10B104KC8NNNC |  |  |  |  |  |  |  |  |
|  |  |  |  | 13 | 13 | 520100200-237-G | - | DIODE,Switching,1N4148W-7-F,100V,0.15A,G,SOD123-2,SMD | DIODES | 1N4148W-7-F | 13 |  | D1,D2,D3,D4,D5,PHAD6,D6,D7,D8,D9,D10,D11,D12 |  |  |  |  |  |
|  |  |  |  | 14 | 14 | 730101C00-086-G |  | Fuse,Slow blow,125V,30A,G,SMD | LITTELFUSE | 0456030.ER | 3 |  | FS1,FS2,FS10 |  |  |  |  |  |
|  |  |  |  | 15 | 15 | 730106S00-088-G |  | Fuse,Fast acting,125V,15A,G,SMD2010 | COOPER | CB61F15A-TR2 | 1 |  | FS3 |  |  |  |  |  |
|  |  |  |  | 16 | 16 | 730103M00-086-G |  | Fuse,Fast acting,32V,5A,G,SMD0603 | LITTELFUSE | 0438005.WR | 6 |  | FS4,FS5,FS6,FS7,FS8,FS9 |  |  |  |  |  |
|  |  |  |  | 17 | 17 | 22-23-2081 |  | CONN,Header,WTB,1X8,V/T,Bla,2.54mm,G,DIP-8 | MOLEX | 22-23-2081 | 6 |  | J4,J5,J6,J7,J8,J9 |  |  |  |  |  |
|  |  |  |  | 18 | 18 | 72010KB01-016-G | - | FB,330 Ohm@100MHz,+/-25%,2.5A,50mOhm,G,SMD0805 | TDK | MPZ2012S331AT | 6 |  | L1,L2,L3,L4,L5,L6 |  |  |  |  |  |
|  |  |  |  | 19 | 19 | 62111CS00-024-G |  | ECAP,68uF,+/-20%,100V,105C,G,SMD12.5*13.5,ESR<=320mOhm | PANASONIC | EEVFK2A680Q | 4 |  | PSUCE1,PEUCE1,PSUCE2,PEUCE2 |  |  |  |  |  |
|  |  |  |  | 20 | 20 | 62120HJ00-022-G |  | ECAP,SPEA,270uF,+/-20%,16V,105C,G,SMD6.3X9.9,ESR<=8mOhm | SANYO | 16SVPG270M | 2 |  | PSUCE4,PEUCE4 |  |  |  |  |  |
|  |  |  |  | 21 | 21 | 62011J601-015-G |  | CAP,2.2uF,+/-10%,X7R,100V,G,SMD1210 | MURATA | GRM32ER72A225K | 4 |  | PSUC1,PEUC1,PSUC2,PEUC2 |  |  |  |  |  |
|  |  |  |  |  | 21 | 62011J600-026-G |  | CAP,2.2uF,+/-10%,X7R,100V,G,SMD1210 | SAMSUNG | CL32B225KCJSNNE |  |  |  |  |  |  |  |  |
|  |  |  |  | 22 | 22 | 62011F100-015-G |  | CAP,1uF,+/-10%,X7R,25V,G,SMD0603 | MURATA | GRM188R71E105K | 2 |  | PSUC4,PEUC4 |  |  |  |  |  |
|  |  |  |  |  | 22 | 62011F100-023-G |  | CAP,1uF,+/-10%,X7R,25V,G,SMD0603 | TAIYO | TMK107B7105KA-T |  |  |  |  |  |  |  |  |
|  |  |  |  |  | 22 | 62011F100-026-G |  | CAP,1uF,+/-10%,X7R,25V,G,SMD0603 | SAMSUNG | CL10B105KA8NNNC |  |  |  |  |  |  |  |  |
|  |  |  |  | 23 | 23 | 62012T500-015-G |  | CAP,22uF,+/-20%,X7S,25V,G,SMD1206 | MURATA | GRM31CC71E226ME11L | 14 |  | PSRC2,PSUC5,PEUC5,PSUC6,PEUC6,PSUC7,PEUC7,PSUC8,PEUC8,PSUC9,PEUC9,PSUC10,PEUC10,PSRC17 |  |  |  |  |  |
|  |  |  |  | 24 | 24 | 51030CQ00-185-G |  | MOS N,2N7002,60V,115mA,7.5ohm@5V,G,SOT23-3,SMD | FAIRCHILD | 2N7002 | 2 |  | PSUQ1,PEUQ1 |  |  |  |  |  |
|  |  |  |  | 25 | 25 | 61010G500-017-G | - | RES,10KOhm,+/-1%,1/16W,G,SMD0402 | KOA | RK73H1ETTP1002F | 22 |  | PEUR1,PSRR6,R23,PHAR23,R119,R121,R131,R133,R138,R159,R162,R172,R174,R183,R185,R195,R197,R234,R1815,R1816,R1817,R1818 |  |  |  |  |  |
|  |  |  |  |  | 25 | 61010G500-012-G |  | RES,10KOhm,+/-1%,1/16W,G,SMD0402 | WALSIN | WR04X1002FTL |  |  |  |  |  |  |  |  |
|  |  |  |  |  | 25 | 61010G500-011-G |  | RES,10KOhm,+/-1%,1/16W,G,SMD0402 | YAGEO | RC0402FR-0710KL |  |  |  |  |  |  |  |  |
|  |  |  |  |  | 25 | 61010G500-044-G |  | RES,10KOhm,+/-1%,1/16W,G,SMD0402 | TA-I | RM04FTN1002 |  |  |  |  |  |  |  |  |
|  |  |  |  |  | 25 | 61010G500-029-G |  | RES,10KOhm,+/-1%,1/16W,G,SMD0402 | VISHAY | CRCW040210K0FKED |  |  |  |  |  |  |  |  |
|  |  |  |  |  | 25 | 61010G500-024-G |  | RES,10KOhm,+/-1%,1/16W,G,SMD0402 | PANASONIC | ERJ2RKF1002X |  |  |  |  |  |  |  |  |
|  |  |  |  | 26 | 26 | 610107A00-017-G | - | RES,0 Ohm,+/-5%,1/16W,G,SMD0402 | KOA | RK73Z1ETTP | 55 |  | R1,R9,PSRR9,R10,PHAR11,PHAR12,PSRR13,PSRR15,PSRR18,PHAR24,PHAR25,R30,R31,PHAR31,PHAR32,PHAR34,R51,R52,R123,R135,R139,R140,R161,R171,R199,R235,R494,R499,PSUR500,PEUR500,PSUR501,PEUR501,R1775,R1781,R1783,R1790,R1791,R1792,R1793,R1794,R1795,R1796,R1797,R1798,R1799,R1800,R1801,R1802,R1803,R1804,R1805,R1806,R1807,R1808,R1813 |  |  |  |  |  |
|  |  |  |  |  | 26 | 610107A00-012-G |  | RES,0 Ohm,+/-5%,1/16W,G,SMD0402 | WALSIN | WR04X000PTL |  |  |  |  |  |  |  |  |
|  |  |  |  |  | 26 | 610107A00-011-G |  | RES,0 Ohm,+/-5%,1/16W,G,SMD0402 | YAGEO | RC0402JR-070RL |  |  |  |  |  |  |  |  |
|  |  |  |  |  | 26 | 610107A00-044-G |  | RES,0 Ohm,+/-5%,1/16W,G,SMD0402 | TA-I | RM04JTN0 |  |  |  |  |  |  |  |  |
|  |  |  |  |  | 26 | 610107A00-024-G |  | RES,0 Ohm,+/-5%,1/16W,G,SMD0402 | PANASONIC | ERJ2GE0R00X |  |  |  |  |  |  |  |  |
|  |  |  |  |  | 26 | 610107A00-029-G |  | RES,0 Ohm,+/-5%,1/16W,G,SMD0402 | VISHAY | CRCW04020000Z0ED |  |  |  |  |  |  |  |  |
|  |  |  |  | 27 | 27 | 880302300-065-G |  | Converter,input 40V~60V,600W,G,Q54SJ12050NNDH | DELTA | Q54SJ12050NNDH | 2 |  | PSUU1,PEUU1 |  |  |  |  |  |
|  |  |  |  | 28 | 28 | 620131D00-015-G |  | CAP,1uF,+/-10%,X6S,16V,G,SMD0402 | MURATA | GRM155C81C105KE11J | 2 |  | PHAC1,PHAC7 |  |  |  |  |  |
|  |  |  |  |  | 28 | 620131D00-023-G |  | CAP,1uF,+/-10%,X6S,16V,G,SMD0402 | TAIYO | EMK105C6105KV-F |  |  |  |  |  |  |  |  |
|  |  |  |  | 29 | 29 | 620133600-015-G |  | CAP,1nF,+/-5%,X7R,100V,G,SMD0805 | MURATA | GRM219R72A102JA01D | 1 |  | PHAC3 |  |  |  |  |  |
|  |  |  |  |  | 29 | 620133600-012-G |  | CAP,1nF,+/-5%,X7R,100V,G,SMD0805 | WALSIN | 0805B102J101CT |  |  |  |  |  |  |  |  |
|  |  |  |  | 30 | 30 | 62010G800-015-G | - | CAP,22nF,+/-10%,X7R,16V,G,SMD0402 | MURATA | GRM155R71C223K | 1 |  | PHAC4 |  |  |  |  |  |
|  |  |  |  |  | 30 | 62010G800-012-G |  | CAP,22nF,+/-10%,X7R,16V,G,SMD0402 | WALSIN | 0402B223K160CT |  |  |  |  |  |  |  |  |
|  |  |  |  |  | 30 | 62010G800-026-G |  | CAP,22nF,+/-10%,X7R,16V,G,SMD0402 | SAMSUNG | CL05B223KO5NNNC |  |  |  |  |  |  |  |  |
|  |  |  |  |  | 30 | 62010G800-023-G |  | CAP,22nF,+/-10%,X7R,16V,G,SMD0402 | TAIYO | EMK105B7223KV-F |  |  |  |  |  |  |  |  |
|  |  |  |  | 31 | 31 | 620135500-015-G |  | CAP,39nF,+/-10%,X7R,100V,G,SMD0805 | MURATA | GRM21BR72A393KA01L | 1 |  | PHAC18 |  |  |  |  |  |
|  |  |  |  |  | 31 | 620135500-012-G |  | CAP,39nF,+/-10%,X7R,100V,G,SMD0805 | WALSIN | 0805B393K101CT |  |  |  |  |  |  |  |  |
|  |  |  |  | 32 | 32 | 52170KE00-086-G |  | TVS Diode,SMCJ64A,G,DO-214AB-2,SMD | LITTELFUSE | SMCJ64A | 1 |  | PHAD1 |  |  |  |  |  |
|  |  |  |  | 33 | 33 | 52030YE00-223-G |  | DIODE,Schottky,MBR5H100MFST1G,100V,5A,G,SO8FL-8,SMD | ON | MBR5H100MFST1G | 1 |  | PHAD2 |  |  |  |  |  |
|  |  |  |  | 34 | 34 | 51031VY00-031-G |  | MOS N,PSMN4R8-100BSE,100V,120A,4.8m@10V,G,SOT404-3,SMD | NXP | PSMN4R8-100BSE | 3 |  | PHAQ1,PHAQ2,PHAQ3 |  |  |  |  |  |
|  |  |  |  | 35 | 35 | 51020A000-031-G |  | TRANS P,PBHV9115T,150V,1A,G,SOT23-3,SMD | NXP | PBHV9115T | 1 |  | PHAQ4 |  |  |  |  |  |
|  |  |  |  | 36 | 36 | 51032D100-237-G |  | MOS N,DMN10H220L-7,100V,1.6A,220m@10V,G,SOT-23-3,SMD | DIODES | DMN10H220L-7 | 2 |  | PHAQ5,PHAQ9 |  |  |  |  |  |
|  |  |  |  | 37 | 37 | 510100W00-237-G | - | TRANS N,MMBT3904-7-F,40V,0.2A,G,SOT23-3,SMD | DIODES | MMBT3904-7-F | 1 |  | PHAQ8 |  |  |  |  |  |
|  |  |  |  | 38 | 38 | 610602200-32D-G |  | RES,0.5mOhm,+/-1%,3W,G,SMD2512 | Thin Film Technology Corporation | CPA1225RR0005FW | 1 |  | PHAR1 |  |  |  |  |  |
|  |  |  |  | 39 | 39 | 61100DA00-017-G |  | RES,33KOhm,+/-0.1%,1/16W,G,SMD0402 | KOA | RN731ETTP3302B25 | 1 |  | PHAR2 |  |  |  |  |  |
|  |  |  |  |  | 39 | 61100DA00-012-G |  | RES,33KOhm,+/-0.1%,1/16W,G,SMD0402 | WALSIN | WF04U3302BTL |  |  |  |  |  |  |  |  |
|  |  |  |  |  | 39 | 61100DA00-011-G |  | RES,33KOhm,+/-0.1%,1/16W,G,SMD0402 | YAGEO | RT0402BRD0733KL |  |  |  |  |  |  |  |  |
|  |  |  |  | 40 | 40 | 610130Y00-017-G |  | RES,1 Ohm,+/-1%,1/3W,G,SMD1206 | KOA | SR732BTTD1R00F | 1 |  | PHAR4 |  |  |  |  |  |
|  |  |  |  |  | 40 | 610122P00-012-G |  | RES,1 Ohm,+/-1%,1/2W,G,SMD1206 | WALSIN | WF12P1R00FTL |  |  |  |  |  |  |  |  |
|  |  |  |  |  | 40 | 610122P00-011-G |  | RES,1 Ohm,+/-1%,1/2W,G,SMD1206 | YAGEO | RC1206FR-7W1RL |  |  |  |  |  |  |  |  |
|  |  |  |  |  | 40 | 610122P00-044-G |  | RES,1 Ohm,+/-1%,1/2W,G,SMD1206 | TA-I | RMH12FT1R00 |  |  |  |  |  |  |  |  |
|  |  |  |  | 41 | 41 | 61100QM00-017-G |  | RES,100KOhm,+/-0.1%,1/10W,G,SMD0603 | KOA | RN73H1JTTD1003B25 | 4 |  | PHAR5,PHAR7,PHAR40,PHAR45 |  |  |  |  |  |
|  |  |  |  |  | 41 | 61100QM00-012-G |  | RES,100KOhm,+/-0.1%,1/10W,G,SMD0603 | WALSIN | WF06Q1003BTL |  |  |  |  |  |  |  |  |
|  |  |  |  |  | 41 | 61100QM00-011-G |  | RES,100KOhm,+/-0.1%,1/10W,G,SMD0603 | YAGEO | RT0603BRD07100KL |  |  |  |  |  |  |  |  |
|  |  |  |  | 42 | 42 | 610100200-017-G | - | RES,7.5KOhm,+/-1%,1/10W,G,SMD0603 | KOA | RK73H1JTTD7501F | 1 |  | PHAR6 |  |  |  |  |  |
|  |  |  |  |  | 42 | 610100200-012-G |  | RES,7.5KOhm,+/-1%,1/10W,G,SMD0603 | WALSIN | WR06X7501FTL |  |  |  |  |  |  |  |  |
|  |  |  |  |  | 42 | 610100200-011-G |  | RES,7.5KOhm,+/-1%,1/10W,G,SMD0603 | YAGEO | RC0603FR-077K5L |  |  |  |  |  |  |  |  |
|  |  |  |  |  | 42 | 610100200-044-G |  | RES,7.5KOhm,+/-1%,1/10W,G,SMD0603 | TA-I | RM06FTN7501 |  |  |  |  |  |  |  |  |
|  |  |  |  | 43 | 43 | 610103Y00-017-G |  | RES,10 Ohm,+/-1%,1/10W,G,SMD0603 | KOA | RK73H1JTTD10R0F | 3 |  | PHAR8,PHAR14,PHAR15 |  |  |  |  |  |
|  |  |  |  |  | 43 | 610103Y00-011-G |  | RES,10 Ohm,+/-1%,1/10W,G,SMD0603 | YAGEO | RC0603FR-0710RL |  |  |  |  |  |  |  |  |
|  |  |  |  |  | 43 | 610103Y00-044-G |  | RES,10 Ohm,+/-1%,1/10W,G,SMD0603 | TA-I | RM06FTN10R0 |  |  |  |  |  |  |  |  |
|  |  |  |  |  | 43 | 610103Y00-012-G |  | RES,10 Ohm,+/-1%,1/10W,G,SMD0603 | WALSIN | WR06X10R0FTL |  |  |  |  |  |  |  |  |
|  |  |  |  |  | 43 | 610103Y00-024-G |  | RES,10 Ohm,+/-1%,1/10W,G,SMD0603 | PANASONIC | ERJ3EKF10R0V |  |  |  |  |  |  |  |  |
|  |  |  |  | 44 | 44 | 61010L300-017-G | - | RES,1KOhm,+/-1%,1/16W,G,SMD0402 | KOA | RK73H1ETTP1001F | 2 |  | PHAR9,PHAR38 |  |  |  |  |  |
|  |  |  |  |  | 44 | 61010L300-012-G |  | RES,1KOhm,+/-1%,1/16W,G,SMD0402 | WALSIN | WR04X1001FTL |  |  |  |  |  |  |  |  |
|  |  |  |  |  | 44 | 61010L300-011-G |  | RES,1KOhm,+/-1%,1/16W,G,SMD0402 | YAGEO | RC0402FR-071KL |  |  |  |  |  |  |  |  |
|  |  |  |  |  | 44 | 61010L300-044-G |  | RES,1KOhm,+/-1%,1/16W,G,SMD0402 | TA-I | RM04FTN1001 |  |  |  |  |  |  |  |  |
|  |  |  |  |  | 44 | 61010L300-024-G |  | RES,1KOhm,+/-1%,1/16W,G,SMD0402 | PANASONIC | ERJ2RKF1001X |  |  |  |  |  |  |  |  |
|  |  |  |  |  | 44 | 61010L300-029-G |  | RES,1KOhm,+/-1%,1/16W,G,SMD0402 | VISHAY | CRCW04021K00FKED |  |  |  |  |  |  |  |  |
|  |  |  |  | 45 | 45 | 61013GW00-017-G |  | RES,150KOhm,+/-1%,1/8W,G,SMD0805 | KOA | RK73H2ATTD1503F | 1 |  | PHAR13 |  |  |  |  |  |
|  |  |  |  |  | 45 | 61013GW00-012-G |  | RES,150KOhm,+/-1%,1/8W,G,SMD0805 | WALSIN | WR08X1503FTL |  |  |  |  |  |  |  |  |
|  |  |  |  |  | 45 | 61013GW00-011-G |  | RES,150KOhm,+/-1%,1/8W,G,SMD0805 | YAGEO | RC0805FR-07150KL |  |  |  |  |  |  |  |  |
|  |  |  |  |  | 45 | 61013GW00-044-G |  | RES,150KOhm,+/-1%,1/8W,G,SMD0805 | TA-I | RM10FTN1503 |  |  |  |  |  |  |  |  |
|  |  |  |  | 46 | 46 | 610114F00-017-G | - | RES,3.16KOhm,+/-1%,1/16W,G,SMD0402 | KOA | RK73H1ETTP3161F | 1 |  | PHAR20 |  |  |  |  |  |
|  |  |  |  |  | 46 | 610114F00-012-G |  | RES,3.16KOhm,+/-1%,1/16W,G,SMD0402 | WALSIN | WR04X3161FTL |  |  |  |  |  |  |  |  |
|  |  |  |  |  | 46 | 610114F00-011-G |  | RES,3.16KOhm,+/-1%,1/16W,G,SMD0402 | YAGEO | RC0402FR-073K16L |  |  |  |  |  |  |  |  |
|  |  |  |  |  | 46 | 610114F00-044-G |  | RES,3.16KOhm,+/-1%,1/16W,G,SMD0402 | TA-I | RM04FTN3161 |  |  |  |  |  |  |  |  |
|  |  |  |  | 47 | 47 | 61011NM00-017-G |  | RES,6.81KOhm,+/-1%,1/16W,G,SMD0402 | KOA | RK73H1ETTP6811F | 1 |  | PHAR22 |  |  |  |  |  |
|  |  |  |  |  | 47 | 61011NM00-012-G |  | RES,6.81KOhm,+/-1%,1/16W,G,SMD0402 | WALSIN | WR04X6811FTL |  |  |  |  |  |  |  |  |
|  |  |  |  |  | 47 | 61011NM00-011-G |  | RES,6.81KOhm,+/-1%,1/16W,G,SMD0402 | YAGEO | RC0402FR-076K81L |  |  |  |  |  |  |  |  |
|  |  |  |  |  | 47 | 61011NM00-044-G |  | RES,6.81KOhm,+/-1%,1/16W,G,SMD0402 | TA-I | RM04FTN6811 |  |  |  |  |  |  |  |  |
|  |  |  |  | 48 | 48 | 61010LA00-017-G | - | RES,4.7KOhm,+/-1%,1/16W,G,SMD0402 | KOA | RK73H1ETTP4701F | 49 |  | R2,R3,R4,R8,R12,R13,R14,R18,R19,R20,R21,R22,R25,R26,R27,R28,PHAR28,R29,PHAR29,PHAR30,R34,R35,R36,R39,R40,R41,R42,R43,R46,R47,R48,R49,R50,R54,R55,R114,R115,R126,R127,R141,R154,R156,R169,R170,R178,R179,R190,R191,R501 |  |  |  |  |  |
|  |  |  |  |  | 48 | 61010LA00-012-G |  | RES,4.7KOhm,+/-1%,1/16W,G,SMD0402 | WALSIN | WR04X4701FTL |  |  |  |  |  |  |  |  |
|  |  |  |  |  | 48 | 61010LA00-011-G |  | RES,4.7KOhm,+/-1%,1/16W,G,SMD0402 | YAGEO | RC0402FR-074K7L |  |  |  |  |  |  |  |  |
|  |  |  |  |  | 48 | 61010LA00-044-G |  | RES,4.7KOhm,+/-1%,1/16W,G,SMD0402 | TA-I | RM04FTN4701 |  |  |  |  |  |  |  |  |
|  |  |  |  | 49 | 49 | 61011PE00-017-G |  | RES,8.87KOhm,+/-1%,1/16W,G,SMD0402 | KOA | RK73H1ETTP8871F | 1 |  | PHAR35 |  |  |  |  |  |
|  |  |  |  |  | 49 | 61011PE00-012-G |  | RES,8.87KOhm,+/-1%,1/16W,G,SMD0402 | WALSIN | WR04X8871FTL |  |  |  |  |  |  |  |  |
|  |  |  |  |  | 49 | 61011PE00-011-G |  | RES,8.87KOhm,+/-1%,1/16W,G,SMD0402 | YAGEO | RC0402FR-078K87L |  |  |  |  |  |  |  |  |
|  |  |  |  |  | 49 | 61011PE00-044-G |  | RES,8.87KOhm,+/-1%,1/16W,G,SMD0402 | TA-I | RM04FTN8871 |  |  |  |  |  |  |  |  |
|  |  |  |  | 50 | 50 | 61010BY00-017-G | - | RES,20KOhm,+/-1%,1/10W,G,SMD0603 | KOA | RK73H1JTTD2002F | 2 |  | PHAR42,PHAR46 |  |  |  |  |  |
|  |  |  |  |  | 50 | 61010BY00-012-G |  | RES,20KOhm,+/-1%,1/10W,G,SMD0603 | WALSIN | WR06X2002FTL |  |  |  |  |  |  |  |  |
|  |  |  |  |  | 50 | 61010BY00-011-G |  | RES,20KOhm,+/-1%,1/10W,G,SMD0603 | YAGEO | RC0603FR-0720KL |  |  |  |  |  |  |  |  |
|  |  |  |  |  | 50 | 61010BY00-044-G |  | RES,20KOhm,+/-1%,1/10W,G,SMD0603 | TA-I | RM06FTN2002 |  |  |  |  |  |  |  |  |
|  |  |  |  | 51 | 51 | 610107H00-017-G |  | RES,4.02KOhm,+/-1%,1/10W,G,SMD0603 | KOA | RK73H1JTTD4021F | 1 |  | PHAR44 |  |  |  |  |  |
|  |  |  |  |  | 51 | 610107H00-012-G |  | RES,4.02KOhm,+/-1%,1/10W,G,SMD0603 | WALSIN | WR06X4021FTL |  |  |  |  |  |  |  |  |
|  |  |  |  |  | 51 | 610107H00-011-G |  | RES,4.02KOhm,+/-1%,1/10W,G,SMD0603 | YAGEO | RC0603FR-074K02L |  |  |  |  |  |  |  |  |
|  |  |  |  |  | 51 | 610107H00-044-G |  | RES,4.02KOhm,+/-1%,1/10W,G,SMD0603 | TA-I | RM06FTN4021 |  |  |  |  |  |  |  |  |
|  |  |  |  | 52 | 52 | 32023RR00-183-G |  | IC,Power Controller,LM5066IPMHX/NOPB,G,HTSSOP-28,SMD | TI | LM5066IPMHX/NOPB | 1 |  | PHAU1 |  |  |  |  |  |
|  |  |  |  | 53 | 53 | 62012GG00-015-G |  | CAP,10uF,+/-10%,X7S,25V,G,SMD0805 | MURATA | GRM21BC71E106K | 1 |  | PSRC3 |  |  |  |  |  |
|  |  |  |  |  | 53 | 62012GG00-012-G |  | CAP,10uF,+/-10%,X7S,25V,G,SMD0805 | WALSIN | 0805A106K250CT |  |  |  |  |  |  |  |  |
|  |  |  |  | 54 | 54 | 62012T300-015-G |  | CAP,1uF,+/-10%,X7S,25V,G,SMD0402 | MURATA | GRM155C71E105KE11D | 1 |  | PSRC4 |  |  |  |  |  |
|  |  |  |  | 55 | 55 | 62012P100-015-G |  | CAP,2.2uF,+/-20%,X7S,10V,G,SMD0402 | MURATA | GRM155C71A225M | 1 |  | PSRC5 |  |  |  |  |  |
|  |  |  |  |  | 55 | 62012P100-012-G |  | CAP,2.2uF,+/-20%,X7S,10V,G,SMD0402 | WALSIN | 0402A225M100CT |  |  |  |  |  |  |  |  |
|  |  |  |  | 56 | 56 | 62012PT00-015-G |  | CAP,22uF,+/-20%,X6S,16V,G,SMD0805 | MURATA | GRM21BC81C226M | 5 |  | PSRC7,PSRC8,PSRC11,PSRC12,PSRC15 |  |  |  |  |  |
|  |  |  |  |  | 56 | 62012PT00-023-G |  | CAP,22uF,+/-20%,X6S,16V,G,SMD0805 | TAIYO | EDK212BC6226MG-T |  |  |  |  |  |  |  |  |
|  |  |  |  | 57 | 57 | 620105U00-015-G | - | CAP,220pF,+/-10%,X7R,50V,G,SMD0402 | MURATA | GRM155R71H221K | 1 |  | PSRC14 |  |  |  |  |  |
|  |  |  |  |  | 57 | 620105U00-012-G |  | CAP,220pF,+/-10%,X7R,50V,G,SMD0402 | WALSIN | 0402B221K500CT |  |  |  |  |  |  |  |  |
|  |  |  |  |  | 57 | 620105U00-026-G |  | CAP,220pF,+/-10%,X7R,50V,G,SMD0402 | SAMSUNG | CL05B221KB5NNNC |  |  |  |  |  |  |  |  |
|  |  |  |  | 58 | 58 | 62012H100-015-G |  | CAP,10uF,+/-20%,X6S,10V,G,SMD0603 | MURATA | GRM188C81A106M | 1 |  | PSRC16 |  |  |  |  |  |
|  |  |  |  |  | 58 | 62012H100-023-G |  | CAP,10uF,+/-20%,X6S,10V,G,SMD0603 | TAIYO | LMK107BC6106MA-T |  |  |  |  |  |  |  |  |
|  |  |  |  |  | 58 | 62012H100-026-G |  | CAP,10uF,+/-20%,X6S,10V,G,SMD0603 | SAMSUNG | CL10X106MP8NRNC |  |  |  |  |  |  |  |  |
|  |  |  |  | 59 | 59 | 72010RE00-015-G |  | FB,26 Ohm@100MHz,+/-25%,6A,7mOhm,G,SMD0603 | MURATA | BLM18KG260TN1D | 1 |  | PSRL1 |  |  |  |  |  |
|  |  |  |  |  | 59 | 72010SJ00-059-G |  | FB,26 Ohm@100MHz,+/-25%,6A,10mOhm,G,SMD0603 | TAI-TECH | HCB1608KF-260T60 |  |  |  |  |  |  |  |  |
|  |  |  |  | 60 | 60 | 63032PP00-088-G |  | IND,4.7uH@100KHz,+/-20%,5.5A,40mOhm,SHLD,G,SMD | COOPER | HCM0703-4R7-R | 1 |  | PSRL2 |  |  |  |  |  |
|  |  |  |  | 61 | 61 | 61011R400-017-G |  | RES,34.8KOhm,+/-1%,1/16W,G,SMD0402 | KOA | RK73H1ETTP3482F | 1 |  | PSRR1 |  |  |  |  |  |
|  |  |  |  |  | 61 | 61011R400-012-G |  | RES,34.8KOhm,+/-1%,1/16W,G,SMD0402 | WALSIN | WR04X3482FTL |  |  |  |  |  |  |  |  |
|  |  |  |  |  | 61 | 61011R400-011-G |  | RES,34.8KOhm,+/-1%,1/16W,G,SMD0402 | YAGEO | RC0402FR-0734K8L |  |  |  |  |  |  |  |  |
|  |  |  |  |  | 61 | 61011R400-044-G |  | RES,34.8KOhm,+/-1%,1/16W,G,SMD0402 | TA-I | RM04FTN3482 |  |  |  |  |  |  |  |  |
|  |  |  |  | 62 | 62 | 610114S00-017-G | - | RES,4.99KOhm,+/-1%,1/16W,G,SMD0402 | KOA | RK73H1ETTP4991F | 1 |  | PSRR3 |  |  |  |  |  |
|  |  |  |  |  | 62 | 610114S00-012-G |  | RES,4.99KOhm,+/-1%,1/16W,G,SMD0402 | WALSIN | WR04X4991FTL |  |  |  |  |  |  |  |  |
|  |  |  |  |  | 62 | 610114S00-011-G |  | RES,4.99KOhm,+/-1%,1/16W,G,SMD0402 | YAGEO | RC0402FR-074K99L |  |  |  |  |  |  |  |  |
|  |  |  |  |  | 62 | 610114S00-044-G |  | RES,4.99KOhm,+/-1%,1/16W,G,SMD0402 | TA-I | RM04FTN4991 |  |  |  |  |  |  |  |  |
|  |  |  |  |  | 62 | 610114S00-024-G |  | RES,4.99KOhm,+/-1%,1/16W,G,SMD0402 | PANASONIC | ERJ2RKF4991X |  |  |  |  |  |  |  |  |
|  |  |  |  | 63 | 63 | 61011HA00-017-G |  | RES,1 Ohm,+/-1%,1/16W,G,SMD0402 | KOA | RK73H1ETTP1R00F | 1 |  | PSRR5 |  |  |  |  |  |
|  |  |  |  |  | 63 | 61011HA00-012-G |  | RES,1 Ohm,+/-1%,1/16W,G,SMD0402 | WALSIN | WR04W1R00FTL |  |  |  |  |  |  |  |  |
|  |  |  |  |  | 63 | 61011HA00-011-G |  | RES,1 Ohm,+/-1%,1/16W,G,SMD0402 | YAGEO | RC0402FR-071RL |  |  |  |  |  |  |  |  |
|  |  |  |  |  | 63 | 61011HA00-044-G |  | RES,1 Ohm,+/-1%,1/16W,G,SMD0402 | TA-I | RM04FTN1R00 |  |  |  |  |  |  |  |  |
|  |  |  |  |  | 63 | 61011HA00-029-G |  | RES,1 Ohm,+/-1%,1/16W,G,SMD0402 | VISHAY | CRCW04021R00FNED |  |  |  |  |  |  |  |  |
|  |  |  |  | 64 | 64 | 611004M00-017-G |  | RES,16.5KOhm,+/-0.1%,1/16W,G,SMD0402 | KOA | RN731ETTP1652B25 | 1 |  | PSRR17 |  |  |  |  |  |
|  |  |  |  |  | 64 | 611004M00-024-G |  | RES,16.5KOhm,+/-0.1%,1/16W,G,SMD0402 | PANASONIC | ERA2AEB1652X |  |  |  |  |  |  |  |  |
|  |  |  |  | 65 | 65 | 61100YB00-017-G |  | RES,2.94KOhm,+/-0.1%,1/16W,G,SMD0402 | KOA | RN731ETTP2941B25 | 1 |  | PSRR19 |  |  |  |  |  |
|  |  |  |  | 66 | 66 | 32013PD00-238-G |  | IC,Regulator,IR3883MTRPbF,ADJ,3A,G,QFN-16,SMD | IR | IR3883MTRPBF | 1 |  | PSRU1 |  |  |  |  |  |
|  |  |  |  | 67 | 67 | 610115R00-017-G |  | RES,15KOhm,+/-1%,1/16W,G,SMD0402 | KOA | RK73H1ETTP1502F | 1 |  | PSUR1 |  |  |  |  |  |
|  |  |  |  |  | 67 | 610115R00-012-G |  | RES,15KOhm,+/-1%,1/16W,G,SMD0402 | WALSIN | WR04X1502FTL |  |  |  |  |  |  |  |  |
|  |  |  |  |  | 67 | 610115R00-011-G |  | RES,15KOhm,+/-1%,1/16W,G,SMD0402 | YAGEO | RC0402FR-0715KL |  |  |  |  |  |  |  |  |
|  |  |  |  |  | 67 | 610115R00-044-G |  | RES,15KOhm,+/-1%,1/16W,G,SMD0402 | TA-I | RM04FTN1502 |  |  |  |  |  |  |  |  |
|  |  |  |  |  | 67 | 610115R00-024-G |  | RES,15KOhm,+/-1%,1/16W,G,SMD0402 | PANASONIC | ERJ2RKF1502X |  |  |  |  |  |  |  |  |
|  |  |  |  |  | 67 | 610115R00-029-G |  | RES,15KOhm,+/-1%,1/16W,G,SMD0402 | VISHAY | CRCW040215K0FKED |  |  |  |  |  |  |  |  |
|  |  |  |  | 68 | 68 | 510503B00-223-G |  | MOS N/N,NTZD3154NT1G,20V,0.54A,550m24.5V,G,SOT563-6,SMD | ON | NTZD3154NT1G | 1 |  | QN4 |  |  |  |  |  |
|  |  |  |  |  | 68 | 51050C700-237-G |  | MOS N/N,DMN2400UV-7,20V,1.33A/0.84A,350m@4.5V,G,SOT563-6,SMD | DIODES | DMN2400UV-7 |  |  |  |  |  |  |  |  |
|  |  |  |  |  | 68 | 51050AK00-030-G |  | MOS N/N,EM6K6T2R,20V,0.3A,1ohm@4V,G,EMT-6,SMD | ROHM | EM6K6T2R |  |  |  |  |  |  |  |  |
|  |  |  |  | 69 | 69 | 510301D00-223-G |  | MOS N,BSS138LT1G,50V,0.2A,3.5ohm@5V,G,SOT23-3,SMD | ON | BSS138LT1G | 12 |  | Q1,Q2,Q3,Q4,Q5,Q6,Q7,Q8,Q9,Q10,Q11,Q12 |  |  |  |  |  |
|  |  |  |  |  | 69 | 510302R00-185-G |  | MOS N,BSS138,50V,0.22A,6ohm@4.5V,G,SOT23-3,SMD | FAIRCHILD | BSS138 |  |  |  |  |  |  |  |  |
|  |  |  |  |  | 69 | 510309C00-237-G |  | MOS N,BSS138-7-F,50V,0.2A,3.5ohm@10V,G,SOT23-3,SMD | DIODES | BSS138-7-F |  |  |  |  |  |  |  |  |
|  |  |  |  |  | 69 | 51030A800-221-G |  | MOS N,BSS138N,60V,0.23A,6ohm@4.5V,G,SOT23-3,SMD | INFINEON | BSS138N |  |  |  |  |  |  |  |  |
|  |  |  |  | 70 | 70 | 51040EK00-185-G |  | MOS P,FDMS6681Z,30V,49A,5m@4.5V,G,Power56-8,SMD | FAIRCHILD | FDMS6681Z | 2 |  | Q13,Q14 |  |  |  |  |  |
|  |  |  |  | 71 | 71 | 61010H800-017-G |  | RES,5.11 Ohm,+/-1%,1/10W,G,SMD0603 | KOA | RK73H1JTTD5R11F | 2 |  | R11,R32 |  |  |  |  |  |
|  |  |  |  |  | 71 | 61010H800-012-G |  | RES,5.11 Ohm,+/-1%,1/10W,G,SMD0603 | WALSIN | WR06W5R11FTL |  |  |  |  |  |  |  |  |
|  |  |  |  |  | 71 | 61010H800-011-G |  | RES,5.11 Ohm,+/-1%,1/10W,G,SMD0603 | YAGEO | RC0603FR-075R11L |  |  |  |  |  |  |  |  |
|  |  |  |  |  | 71 | 61010H800-044-G |  | RES,5.11 Ohm,+/-1%,1/10W,G,SMD0603 | TA-I | RM06FTN5R11 |  |  |  |  |  |  |  |  |
|  |  |  |  | 72 | 72 | 61011MQ00-017-G | - | RES,4.75KOhm,+/-1%,1/16W,G,SMD0402 | KOA | RK73H1ETTP4751F | 4 |  | R15,R33,R1772,R1814 |  |  |  |  |  |
|  |  |  |  |  | 72 | 61011MQ00-012-G |  | RES,4.75KOhm,+/-1%,1/16W,G,SMD0402 | WALSIN | WR04X4751FTL |  |  |  |  |  |  |  |  |
|  |  |  |  |  | 72 | 61011MQ00-011-G |  | RES,4.75KOhm,+/-1%,1/16W,G,SMD0402 | YAGEO | RC0402FR-074K75L |  |  |  |  |  |  |  |  |
|  |  |  |  |  | 72 | 61011MQ00-044-G |  | RES,4.75KOhm,+/-1%,1/16W,G,SMD0402 | TA-I | RM04FTN4751 |  |  |  |  |  |  |  |  |
|  |  |  |  | 73 | 73 | 610115J00-017-G | - | RES,33 Ohm,+/-1%,1/16W,G,SMD0402 | KOA | RK73H1ETTP33R0F | 2 |  | R17,R37 |  |  |  |  |  |
|  |  |  |  |  | 73 | 610115J00-012-G |  | RES,33 Ohm,+/-1%,1/16W,G,SMD0402 | WALSIN | WR04X33R0FTL |  |  |  |  |  |  |  |  |
|  |  |  |  |  | 73 | 610115J00-011-G |  | RES,33 Ohm,+/-1%,1/16W,G,SMD0402 | YAGEO | RC0402FR-0733RL |  |  |  |  |  |  |  |  |
|  |  |  |  |  | 73 | 610115J00-044-G |  | RES,33 Ohm,+/-1%,1/16W,G,SMD0402 | TA-I | RM04FTN33R0 |  |  |  |  |  |  |  |  |
|  |  |  |  |  | 73 | 610115J00-024-G |  | RES,33 Ohm,+/-1%,1/16W,G,SMD0402 | PANASONIC | ERJ2RKF33R0X |  |  |  |  |  |  |  |  |
|  |  |  |  | 74 | 74 | 61010L100-017-G | - | RES,100KOhm,+/-1%,1/16W,G,SMD0402 | KOA | RK73H1ETTP1003F | 3 |  | R45,R233,R236 |  |  |  |  |  |
|  |  |  |  |  | 74 | 61010L100-012-G |  | RES,100KOhm,+/-1%,1/16W,G,SMD0402 | WALSIN | WR04X1003FTL |  |  |  |  |  |  |  |  |
|  |  |  |  |  | 74 | 61010L100-011-G |  | RES,100KOhm,+/-1%,1/16W,G,SMD0402 | YAGEO | RC0402FR-07100KL |  |  |  |  |  |  |  |  |
|  |  |  |  |  | 74 | 61010L100-044-G |  | RES,100KOhm,+/-1%,1/16W,G,SMD0402 | TA-I | RM04FTN1003 |  |  |  |  |  |  |  |  |
|  |  |  |  |  | 74 | 61010L106-029-G |  | RES,100KOhm,+/-1%,1/16W,G,SMD0402 | VISHAY | CRCW0402100KFKEDC |  |  |  |  |  |  |  |  |
|  |  |  |  |  | 74 | 61010L100-024-G |  | RES,100KOhm,+/-1%,1/16W,G,SMD0402 | PANASONIC | ERJ2RKF1003X |  |  |  |  |  |  |  |  |
|  |  |  |  | 75 | 75 | 610103300-017-G | - | RES,100KOhm,+/-5%,1/16W,G,SMD0402 | KOA | RK73B1ETTP104J | 18 |  | R58,R60,R62,R64,R66,R68,R72,R74,R76,R78,R80,R82,R86,R88,R90,R92,R94,R96 |  |  |  |  |  |
|  |  |  |  |  | 75 | 610103300-012-G |  | RES,100KOhm,+/-5%,1/16W,G,SMD0402 | WALSIN | WR04X104JTL |  |  |  |  |  |  |  |  |
|  |  |  |  |  | 75 | 610103300-011-G |  | RES,100KOhm,+/-5%,1/16W,G,SMD0402 | YAGEO | RC0402JR-07100KL |  |  |  |  |  |  |  |  |
|  |  |  |  |  | 75 | 610103300-044-G |  | RES,100KOhm,+/-5%,1/16W,G,SMD0402 | TA-I | RM04JTN104 |  |  |  |  |  |  |  |  |
|  |  |  |  |  | 75 | 610103300-029-G |  | RES,100KOhm,+/-5%,1/16W,G,SMD0402 | VISHAY | CRCW0402100KJNED |  |  |  |  |  |  |  |  |
|  |  |  |  | 76 | 76 | 61011DR00-017-G |  | RES,2.2KOhm,+/-1%,1/16W,G,SMD0402 | KOA | RK73H1ETTP2201F | 24 |  | R59,R61,R73,R75,R87,R89,R116,R117,R118,R128,R129,R130,R155,R157,R158,R166,R167,R168,R180,R181,R182,R192,R193,R194 |  |  |  |  |  |
|  |  |  |  |  | 76 | 61011DR00-012-G |  | RES,2.2KOhm,+/-1%,1/16W,G,SMD0402 | WALSIN | WR04X2201FTL |  |  |  |  |  |  |  |  |
|  |  |  |  |  | 76 | 61011DR00-011-G |  | RES,2.2KOhm,+/-1%,1/16W,G,SMD0402 | YAGEO | RC0402FR-072K2L |  |  |  |  |  |  |  |  |
|  |  |  |  |  | 76 | 61011DR00-044-G |  | RES,2.2KOhm,+/-1%,1/16W,G,SMD0402 | TA-I | RM04FTN2201 |  |  |  |  |  |  |  |  |
|  |  |  |  |  | 76 | 61011DR00-029-G |  | RES,2.2KOhm,+/-1%,1/16W,G,SMD0402 | VISHAY | CRCW04022K20FKED |  |  |  |  |  |  |  |  |
|  |  |  |  | 77 | 77 | 61011DG01-017-G |  | RES,10KOhm,+/-1%,1/20W,G,SMD0201 | KOA | RK73H1HTTC1002F | 6 |  | R98,R99,R106,R107,R110,R112 |  |  |  |  |  |
|  |  |  |  |  | 77 | 61011DG00-012-G |  | RES,10KOhm,+/-1%,1/20W,G,SMD0201 | WALSIN | WR02X1002FAL |  |  |  |  |  |  |  |  |
|  |  |  |  |  | 77 | 61011DG00-011-G |  | RES,10KOhm,+/-1%,1/20W,G,SMD0201 | YAGEO | RC0201FR-0710KL |  |  |  |  |  |  |  |  |
|  |  |  |  |  | 77 | 61011DG00-044-G |  | RES,10KOhm,+/-1%,1/20W,G,SMD0201 | TA-I | RM02FTN1002 |  |  |  |  |  |  |  |  |
|  |  |  |  | 78 | 78 | 61011DL01-017-G | - | RES,1KOhm,+/-1%,1/20W,G,SMD0201 | KOA | RK73H1HTTC1001F | 2 |  | R100,R102 |  |  |  |  |  |
|  |  |  |  |  | 78 | 61011DL00-012-G |  | RES,1KOhm,+/-1%,1/20W,G,SMD0201 | WALSIN | WR02X1001FAL |  |  |  |  |  |  |  |  |
|  |  |  |  |  | 78 | 61011DL00-011-G |  | RES,1KOhm,+/-1%,1/20W,G,SMD0201 | YAGEO | RC0201FR-071KL |  |  |  |  |  |  |  |  |
|  |  |  |  |  | 78 | 61011DL00-044-G |  | RES,1KOhm,+/-1%,1/20W,G,SMD0201 | TA-I | RM02FTN1001 |  |  |  |  |  |  |  |  |
|  |  |  |  | 79 | 79 | 61010AN00-017-G |  | RES,1MOhm,+/-5%,1/16W,G,SMD0402 | KOA | RK73B1ETTP105J | 2 |  | R101,R103 |  |  |  |  |  |
|  |  |  |  |  | 79 | 61010AN00-012-G |  | RES,1MOhm,+/-5%,1/16W,G,SMD0402 | WALSIN | WR04X105JTL |  |  |  |  |  |  |  |  |
|  |  |  |  |  | 79 | 61010AN00-011-G |  | RES,1MOhm,+/-5%,1/16W,G,SMD0402 | YAGEO | RC0402JR-071ML |  |  |  |  |  |  |  |  |
|  |  |  |  |  | 79 | 61010AN00-044-G |  | RES,1MOhm,+/-5%,1/16W,G,SMD0402 | TA-I | RM04JTN105 |  |  |  |  |  |  |  |  |
|  |  |  |  | 80 | 80 | 610132800-017-G |  | RES,1.54KOhm,+/-1%,1/20W,G,SMD0201 | KOA | RK73H1HTTC1541F | 2 |  | R104,R105 |  |  |  |  |  |
|  |  |  |  |  | 80 | 610132800-012-G |  | RES,1.54KOhm,+/-1%,1/20W,G,SMD0201 | WALSIN | WR02X1541FAL |  |  |  |  |  |  |  |  |
|  |  |  |  |  | 80 | 610132800-044-G |  | RES,1.54KOhm,+/-1%,1/20W,G,SMD0201 | TA-I | RM02FTN1541 |  |  |  |  |  |  |  |  |
|  |  |  |  | 81 | 81 | 610113T00-017-G | - | RES,13.7KOhm,+/-1%,1/16W,G,SMD0402 | KOA | RK73H1ETTP1372F | 2 |  | R108,R109 |  |  |  |  |  |
|  |  |  |  |  | 81 | 610113T00-012-G |  | RES,13.7KOhm,+/-1%,1/16W,G,SMD0402 | WALSIN | WR04X1372FTL |  |  |  |  |  |  |  |  |
|  |  |  |  |  | 81 | 610113T00-011-G |  | RES,13.7KOhm,+/-1%,1/16W,G,SMD0402 | YAGEO | RC0402FR-0713K7L |  |  |  |  |  |  |  |  |
|  |  |  |  |  | 81 | 610113T00-044-G |  | RES,13.7KOhm,+/-1%,1/16W,G,SMD0402 | TA-I | RM04FTN1372 |  |  |  |  |  |  |  |  |
|  |  |  |  | 82 | 82 | 61011KY00-017-G |  | RES,3.83KOhm,+/-1%,1/16W,G,SMD0402 | KOA | RK73H1ETTP3831F | 2 |  | R111,R113 |  |  |  |  |  |
|  |  |  |  |  | 82 | 61011KY00-012-G |  | RES,3.83KOhm,+/-1%,1/16W,G,SMD0402 | WALSIN | WR04X3831FTL |  |  |  |  |  |  |  |  |
|  |  |  |  |  | 82 | 61011KY00-011-G |  | RES,3.83KOhm,+/-1%,1/16W,G,SMD0402 | YAGEO | RC0402FR-073K83L |  |  |  |  |  |  |  |  |
|  |  |  |  |  | 82 | 61011KY00-044-G |  | RES,3.83KOhm,+/-1%,1/16W,G,SMD0402 | TA-I | RM04FTN3831 |  |  |  |  |  |  |  |  |
|  |  |  |  |  | 82 | 61011KY00-029-G |  | RES,3.83KOhm,+/-1%,1/16W,G,SMD0402 | VISHAY | CRCW04023K83FKED |  |  |  |  |  |  |  |  |
|  |  |  |  | 83 | 83 | 61100LR00-017-G |  | RES,100 Ohm,+/-1%,1/16W,G,SMD0402 | KOA | RN731ETTP1000F50 | 14 |  | R120,R122,R132,R134,R160,R163,R173,R175,R184,R186,R196,R198,R500,R1779 |  |  |  |  |  |
|  |  |  |  |  | 83 | 61100LR00-012-G |  | RES,100 Ohm,+/-1%,1/16W,G,SMD0402 | WALSIN | WF04T1000FTL |  |  |  |  |  |  |  |  |
|  |  |  |  |  | 83 | 61100LR01-011-G |  | RES,100 Ohm,+/-1%,1/16W,G,SMD0402 | YAGEO | RT0402FRE07100RL |  |  |  |  |  |  |  |  |
|  |  |  |  |  | 83 | 61100LR00-044-G |  | RES,100 Ohm,+/-1%,1/16W,G,SMD0402 | TA-I | RB04FTS1000 |  |  |  |  |  |  |  |  |
|  |  |  |  | 84 | 84 | 61011CY00-017-G |  | RES,5.6KOhm,+/-1%,1/16W,G,SMD0402 | KOA | RK73H1ETTP5601F | 12 |  | R124,R125,R136,R137,R164,R165,R176,R177,R188,R189,R200,R201 |  |  |  |  |  |
|  |  |  |  |  | 84 | 61011CY00-012-G |  | RES,5.6KOhm,+/-1%,1/16W,G,SMD0402 | WALSIN | WR04X5601FTL |  |  |  |  |  |  |  |  |
|  |  |  |  |  | 84 | 61011CY00-011-G |  | RES,5.6KOhm,+/-1%,1/16W,G,SMD0402 | YAGEO | RC0402FR-075K6L |  |  |  |  |  |  |  |  |
|  |  |  |  |  | 84 | 61011CY00-044-G |  | RES,5.6KOhm,+/-1%,1/16W,G,SMD0402 | TA-I | RM04FTN5601 |  |  |  |  |  |  |  |  |
|  |  |  |  |  | 84 | 61011CY00-029-G |  | RES,5.6KOhm,+/-1%,1/16W,G,SMD0402 | VISHAY | CRCW04025K60FKED |  |  |  |  |  |  |  |  |
|  |  |  |  | 85 | 85 | 61011QD00-017-G | - | RES,330 Ohm,+/-1%,1/16W,G,SMD0402 | KOA | RK73H1ETTP3300F | 12 |  | R142,R143,R144,R145,R146,R147,R148,R149,R150,R151,R152,R153 |  |  |  |  |  |
|  |  |  |  |  | 85 | 61011QD00-012-G |  | RES,330 Ohm,+/-1%,1/16W,G,SMD0402 | WALSIN | WR04X3300FTL |  |  |  |  |  |  |  |  |
|  |  |  |  |  | 85 | 61011QD00-011-G |  | RES,330 Ohm,+/-1%,1/16W,G,SMD0402 | YAGEO | RC0402FR-07330RL |  |  |  |  |  |  |  |  |
|  |  |  |  |  | 85 | 61011QD00-044-G |  | RES,330 Ohm,+/-1%,1/16W,G,SMD0402 | TA-I | RM04FTN3300 |  |  |  |  |  |  |  |  |
|  |  |  |  | 86 | 86 | 61011H500-017-G | - | RES,22 Ohm,+/-1%,1/16W,G,SMD0402 | KOA | RK73H1ETTP22R0F | 1 |  | R202 |  |  |  |  |  |
|  |  |  |  |  | 86 | 61011H500-012-G |  | RES,22 Ohm,+/-1%,1/16W,G,SMD0402 | WALSIN | WR04X22R0FTL |  |  |  |  |  |  |  |  |
|  |  |  |  |  | 86 | 61011H500-011-G |  | RES,22 Ohm,+/-1%,1/16W,G,SMD0402 | YAGEO | RC0402FR-0722RL |  |  |  |  |  |  |  |  |
|  |  |  |  |  | 86 | 61011H500-044-G |  | RES,22 Ohm,+/-1%,1/16W,G,SMD0402 | TA-I | RM04FTN22R0 |  |  |  |  |  |  |  |  |
|  |  |  |  |  | 86 | 61011H500-024-G |  | RES,22 Ohm,+/-1%,1/16W,G,SMD0402 | PANASONIC | ERJ2RKF22R0X |  |  |  |  |  |  |  |  |
|  |  |  |  | 87 | 87 | 61010JY00-017-G | - | RES,220 Ohm,+/-5%,1/16W,G,SMD0402 | KOA | RK73B1ETTP221J | 3 |  | R203,R1770,R1771 |  |  |  |  |  |
|  |  |  |  |  | 87 | 61010JY00-012-G |  | RES,220 Ohm,+/-5%,1/16W,G,SMD0402 | WALSIN | WR04X221JTL |  |  |  |  |  |  |  |  |
|  |  |  |  |  | 87 | 61010JY00-011-G |  | RES,220 Ohm,+/-5%,1/16W,G,SMD0402 | YAGEO | RC0402JR-07220RL |  |  |  |  |  |  |  |  |
|  |  |  |  |  | 87 | 61010JY00-044-G |  | RES,220 Ohm,+/-5%,1/16W,G,SMD0402 | TA-I | RM04JTN221 |  |  |  |  |  |  |  |  |
|  |  |  |  | 88 | 88 | 61011CM00-017-G | - | RES,69.8KOhm,+/-1%,1/16W,G,SMD0402 | KOA | RK73H1ETTP6982F | 3 |  | R1809,R1810,R1812 |  |  |  |  |  |
|  |  |  |  |  | 88 | 61011CM00-012-G |  | RES,69.8KOhm,+/-1%,1/16W,G,SMD0402 | WALSIN | WR04X6982FTL |  |  |  |  |  |  |  |  |
|  |  |  |  |  | 88 | 61011CM00-011-G |  | RES,69.8KOhm,+/-1%,1/16W,G,SMD0402 | YAGEO | RC0402FR-0769K8L |  |  |  |  |  |  |  |  |
|  |  |  |  |  | 88 | 61011CM00-044-G |  | RES,69.8KOhm,+/-1%,1/16W,G,SMD0402 | TA-I | RM04FTN6982 |  |  |  |  |  |  |  |  |
|  |  |  |  | 89 | 89 | 610113W00-017-G |  | RES,12.1KOhm,+/-1%,1/16W,G,SMD0402 | KOA | RK73H1ETTP1212F | 1 |  | R1811 |  |  |  |  |  |
|  |  |  |  |  | 89 | 610113W00-012-G |  | RES,12.1KOhm,+/-1%,1/16W,G,SMD0402 | WALSIN | WR04X1212FTL |  |  |  |  |  |  |  |  |
|  |  |  |  |  | 89 | 610113W00-011-G |  | RES,12.1KOhm,+/-1%,1/16W,G,SMD0402 | YAGEO | RC0402FR-0712K1L |  |  |  |  |  |  |  |  |
|  |  |  |  |  | 89 | 610113W00-044-G |  | RES,12.1KOhm,+/-1%,1/16W,G,SMD0402 | TA-I | RM04FTN1212 |  |  |  |  |  |  |  |  |
|  |  |  |  | 90 | 90 | 41040HW00-191-G |  | EEPROM,AT24C02D-SSHM-T,1.7~3.6V,2K,I2C,G,SOIC-8,SMD | ATMEL | AT24C02D-SSHM-T | 1 |  | U_FPDB_FRU |  |  |  |  |  |
|  |  |  |  |  | 90 | 410401W00-214-G |  | EEPROM,M24C02-WMN6TP,2.5~5.5V,256*8,I2C,G,SOIC-8,SMD | ST | M24C02-WMN6TP |  |  |  |  |  |  |  |  |
|  |  |  |  |  | 90 | 41040CW00-232-G |  | EEPROM,24AA024-I/SN,1.7~5.5V,2K,I2C,G,SOIC-8,SMD | MICROCHIP | 24AA024-I/SN |  |  |  |  |  |  |  |  |
|  |  |  |  | 91 | 91 | 320403K00-183-G | - | IC,Temp Sensor,TMP75AIDR,3°C,G,SOIC-8,SMD | TI | TMP75AIDR | 1 |  | U_TMP_R |  |  |  |  |  |
|  |  |  |  |  | 91 | 320404J00-190-G |  | IC,Temp Sensor,ADT75ARZ-REEL,1°C,G,SOIC-8,SMD | ANALOG DEVICES INC | ADT75ARZ-REEL |  |  |  |  |  |  |  |  |
|  |  |  |  | 92 | 92 | 311004800-031-G |  | IC,Translator,PCA9617ADPJ,0.8~5.5V,2.2~5.5V,G,TSSOP-8,SMD | NXP | PCA9617ADPJ | 1 |  | U1 |  |  |  |  |  |
|  |  |  |  |  | 92 | 311004V00-223-G |  | Logic IC,Translator,PCA9617ADMR2G,Vcca=0.8V~5.5V,Vccb=2.2V~5.5V,102ns,Micro8,8P,G | ON | PCA9617ADMR2G |  |  |  |  |  |  |  |  |
|  |  |  |  |  | 92 | 311004K00-183-G |  | Logic IC,Translator,TCA9617ADGKR,Vcca=0.8V~5.5V;Vccb=2.2V~5.5V,250ns,VSSOP,8P,G | TI | TCA9617ADGKR |  |  |  |  |  |  |  |  |
|  |  |  |  |  | 92 | 311004U00-252-G |  | Logic IC,Translator,PI6ULS5V9617AUEX,Vcca=0.8V~5.5V,Vccb=2.2V~5.5V,102ns,MSOP,8P,G | PERICOM | PI6ULS5V9617AUEX |  |  |  |  |  |  |  |  |
|  |  |  |  | 93 | 93 | 310204100-183-G | - | IC,Gate&Inverter,SN74LVC1G14DCKR,1.65~5.5V,G,SC70-5,SMD | TI | SN74LVC1G14DCKR | 1 |  | U2 |  |  |  |  |  |
|  |  |  |  | 94 | 94 | 32040QL00-09N-G |  | IC,Temp Sensor,A,NCT7904D,N/A,G,LQFP-48,SMD | Nuvoton | NCT7904D | 2 |  | U3,U4 |  |  |  |  |  |
|  |  |  |  | 95 | 95 | 31010DT00-031-G |  | IC,Gate,74LVC1G02GW,1.65~5.5V,G,SC88A-5,SMD | NXP | 74LVC1G02GW | 1 |  | U5 |  |  |  |  |  |
|  |  |  |  | 96 | 96 | 310502800-031-G |  | IC,Buffer,74LVC1G07GW,1.65~5.5V,G,SOT353-5,SMD | NXP | 74LVC1G07GW | 8 |  | U6,U8,U19,U20,U21,U22,U23,U24 |  |  |  |  |  |
|  |  |  |  | 97 | 97 | 31010SB00-183-G |  | Logic IC,Gate,ISO1540DR,3V~5.5V,G,SOIC-8,SMD | TI | ISO1540DR | 1 |  | U7 |  |  |  |  |  |
|  |  |  |  | 98 | 98 | 32022DM00-09N-G |  | IC,Power Controller,NCT7368S,G,SOP-8,SMD | Nuvoton | NCT7368S | 6 |  | U9,U10,U11,U12,U13,U14 |  |  |  |  |  |
|  |  |  |  | 99 | 99 | 310500U00-183-G | - | IC,Buffer,SN74LVC07APWR,1.65~5V,G,TSSOP-14,SMD | TI | SN74LVC07APWR | 1 |  | U15 |  |  |  |  |  |
|  |  |  |  | 100 | 100 | 320306E00-183-G |  | IC,Comparator,LMV331IDBVR,9mV,G,SOT23-5,SMD | TI | LMV331IDBVR | 2 |  | U16,U17 |  |  |  |  |  |
|  |  |  |  | 101 | 101 | 210204300-031-G |  | IC,NXP,PCA9535PW,G,TSSOP-24,SMD | NXP | PCA9535PW | 1 |  | U18 |  |  |  |  |  |
|  |  |  |  | 102 | 102 | 320245F00-173-G |  | IC,Power Controller,MAX6456UT29S+T,G,SOT-23-6,SMD | MAXIM | MAX6456UT29S+T | 1 |  | PHAU2 |  |  |  |  |  |
|  |  |  |  | 103 | 103 | 71020KL00-100-G | - | OSC,33MHz,+/-50ppm,3.3V,15pF,G,SMD | TXC | 7X33000013 | 2 |  | Y1,Y2 |  |  |  |  |  |
|  |  |  |  | 104 | 104 | 340636700-600-G |  | CONN,Header,Power,2X8,V/T,Whi,4.2mm,G,DIP-16 | FOXCONN | HM3508E-HP1 | 1 |  | J_EXP_PWR1 |  |  |  |  |  |
|  |  |  |  | 105 | 105 | 340636800-600-G |  | CONN,Header,Power,2X9,V/T,Whi,4.2mm,G,DIP-18 | FOXCONN | HM3509E-HP1 | 1 |  | J_GPU_PWR1 |  |  |  |  |  |
|  |  |  |  | 106 | 106 | 340612R00-309-G | - | CONN,Jumper,Bla,2.54mm,G,DIP-2 | SAMTEC INC. | SNT-100-BK-G | 1 |  | J_PS_ON_SW(2-3)1 |  |  |  |  |  |
|  |  |  |  |  | 106 | 34065L900-GRT-G |  | CONN,jumper,Bla,2.54mm,30u,G,DIP-2 | PINREX | 201-71-01DB00 |  |  |  |  |  |  |  |  |
|  |  |  |  | 107 | 107 | 340600S00-600-G | - | CONN,Pin Header,1X3,V/T,Bla,2.54mm,15u,G,DIP-3 | FOXCONN | HB1103V | 1 |  | J_PS_ON1 |  |  |  |  |  |
|  |  |  |  |  | 107 | 34060WK00-317-G |  | CONN.Pin Header,1X3,V/T,Bla,2.54mm,15u,G,DIP-3 | MOLEX | 87891-0304 |  |  |  |  |  |  |  |  |
|  |  |  |  |  | 107 | 34065R700-GRT-G |  | CONN,Pin Header,1X3,V/T,Bla,2.54mm,15u,G,DIP-3 | PINREX | 21K-81-03HB01 |  |  |  |  |  |  |  |  |
|  |  |  |  |  | 107 | 34065RR00-245-G |  | CONN,Pin Header,1X3,V/T,Bla,2.54mm,15u,G,DIP-3 | AMPHENOL | G800305005EU |  |  |  |  |  |  |  |  |
|  |  |  |  | 108 | 108 | 34044PP00-G78-G |  | CONN,I/O,Terminal Blocks,R/A,Bla,4mm,G,DIP-4 | FCI | VP02650700J0G | 1 |  | J_TERMINAL_GND1 |  |  |  |  |  |
|  |  |  |  | 109 | 109 | 34044PQ00-G78-G |  | CONN,I/O,Terminal Blocks,R/A,Red,4mm,G,DIP-4 | FCI | VP02652700J0G | 1 |  | J_TERMINAL_48V1 |  |  |  |  |  |
|  |  |  |  | 110 | 110 | 3406ANQ00-317-G |  | CONN,Header,Power,V/T,Bla,10mm,30u,G,DIP-8 | MOLEX | 42819-4213 | 1 |  | J1 |  |  |  |  |  |
|  |  |  |  | 111 | 111 | 3406ALY00-317-G |  | CONN,Header,Shrouded,2X6,V/T,Bla,2mm,30u,G,SMD-12 | MOLEX | 87832-5523 | 1 |  | J2 |  |  |  |  |  |
|  |  |  |  | 112 | 112 | 3406ALW00-317-G |  | CONN,Header,Shrouded,2X5,V/T,Bla,2mm,30u,G,SMD-10 | MOLEX | 87832-5423 | 1 | N | J3 |  |  |  |  |  |
